(kicad_pcb
	(version 20260206)
	(generator "pcbnew")
	(generator_version "10.0")
	(general
		(thickness 1.6)
		(legacy_teardrops no)
	)
	(paper "A4")
	(title_block
		(title "01162023_DA0F0TEBIF0_F0T_Expander_BD_F_brd_V02_OCP.brd")
		(comment 1 "Grand Teton / footprints 6767-6774 of 9728")
	)
	(layers
		(0 "F.Cu" signal "TOP")
		(4 "In1.Cu" signal "GND")
		(6 "In2.Cu" signal "VCC")
		(8 "In3.Cu" signal "VCC1")
		(10 "In4.Cu" signal "GND1")
		(12 "In5.Cu" signal "IN1")
		(14 "In6.Cu" signal "GND2")
		(16 "In7.Cu" signal "IN2")
		(18 "In8.Cu" signal "GND3")
		(20 "In9.Cu" signal "IN3")
		(22 "In10.Cu" signal "GND4")
		(24 "In11.Cu" signal "IN4")
		(26 "In12.Cu" signal "GND5")
		(28 "In13.Cu" signal "IN5")
		(30 "In14.Cu" signal "GND6")
		(32 "In15.Cu" signal "IN6")
		(34 "In16.Cu" signal "GND7")
		(2 "B.Cu" signal "BOTTOM")
		(9 "F.Adhes" user "F.Adhesive")
		(11 "B.Adhes" user "B.Adhesive")
		(13 "F.Paste" user "Package Geometry/Pastemask Top")
		(15 "B.Paste" user "Package Geometry/Pastemask Bottom")
		(5 "F.SilkS" user "Ref Des/Silkscreen Top")
		(7 "B.SilkS" user "Ref Des/Silkscreen Bottom")
		(1 "F.Mask" user "Board Geometry/Soldermask Top")
		(3 "B.Mask" user "Board Geometry/Soldermask Bottom")
		(17 "Dwgs.User" user "User.Drawings")
		(19 "Cmts.User" user "User.Comments")
		(21 "Eco1.User" user "User.Eco1")
		(23 "Eco2.User" user "User.Eco2")
		(25 "Edge.Cuts" user "Board Geometry/Outline")
		(27 "Margin" user)
		(31 "F.CrtYd" user "Package Geometry/Place Bound Top")
		(29 "B.CrtYd" user "Package Geometry/Place Bound Bottom")
		(35 "F.Fab" user "Ref Des/Assembly Top")
		(33 "B.Fab" user "Ref Des/Assembly Bottom")
	)
	(footprint ""
		(layer "F.Cu")
		(at 456.532996 -235.191046 90)
		(property "Reference" "R6611"
			(at 0 0 90)
			(layer "F.SilkS")
			(hide yes)
			(effects
				(font
					(size 1.27 1.27)
				)
			)
		)
		(property "Value" ""
			(at 0 0 90)
			(layer "F.Fab")
			(effects
				(font
					(size 1.27 1.27)
				)
			)
		)
		(duplicate_pad_numbers_are_jumpers no)
		(fp_line
			(start 0.7874 -0.4064)
			(end 0.7874 0.4064)
			(stroke
				(width 0.1524)
				(type default)
			)
			(layer "F.SilkS")
		)
		(fp_line
			(start -0.7874 -0.4064)
			(end 0.7874 -0.4064)
			(stroke
				(width 0.1524)
				(type default)
			)
			(layer "F.SilkS")
		)
		(fp_line
			(start 0.7874 0.4064)
			(end -0.7874 0.4064)
			(stroke
				(width 0.1524)
				(type default)
			)
			(layer "F.SilkS")
		)
		(fp_line
			(start -0.7874 0.4064)
			(end -0.7874 -0.4064)
			(stroke
				(width 0.1524)
				(type default)
			)
			(layer "F.SilkS")
		)
		(fp_line
			(start -0.12065 -0.305054)
			(end -0.12065 -0.2794)
			(stroke
				(width 0.1)
				(type default)
			)
			(layer "F.Fab")
		)
		(fp_line
			(start -0.67945 -0.305054)
			(end -0.12065 -0.305054)
			(stroke
				(width 0.1)
				(type default)
			)
			(layer "F.Fab")
		)
		(fp_line
			(start 0.67945 -0.3048)
			(end 0.67945 0.3048)
			(stroke
				(width 0.1)
				(type default)
			)
			(layer "F.Fab")
		)
		(fp_line
			(start 0.12065 -0.3048)
			(end 0.67945 -0.3048)
			(stroke
				(width 0.1)
				(type default)
			)
			(layer "F.Fab")
		)
		(fp_line
			(start 0.12065 -0.2794)
			(end 0.12065 -0.3048)
			(stroke
				(width 0.1)
				(type default)
			)
			(layer "F.Fab")
		)
		(fp_line
			(start -0.12065 -0.2794)
			(end 0.12065 -0.2794)
			(stroke
				(width 0.1)
				(type default)
			)
			(layer "F.Fab")
		)
		(fp_line
			(start 0.120396 0.2794)
			(end -0.12065 0.2794)
			(stroke
				(width 0.1)
				(type default)
			)
			(layer "F.Fab")
		)
		(fp_line
			(start -0.12065 0.2794)
			(end -0.12065 0.3048)
			(stroke
				(width 0.1)
				(type default)
			)
			(layer "F.Fab")
		)
		(fp_line
			(start 0.67945 0.3048)
			(end 0.120396 0.3048)
			(stroke
				(width 0.1)
				(type default)
			)
			(layer "F.Fab")
		)
		(fp_line
			(start 0.120396 0.3048)
			(end 0.120396 0.2794)
			(stroke
				(width 0.1)
				(type default)
			)
			(layer "F.Fab")
		)
		(fp_line
			(start -0.12065 0.3048)
			(end -0.67945 0.3048)
			(stroke
				(width 0.1)
				(type default)
			)
			(layer "F.Fab")
		)
		(fp_line
			(start -0.67945 0.3048)
			(end -0.67945 -0.305054)
			(stroke
				(width 0.1)
				(type default)
			)
			(layer "F.Fab")
		)
		(pad "1" smd circle
			(at -0.40005 0 90)
			(size 0 0)
			(layers "F.Cu" "F.Mask" "F.Paste")
			(net "UART_PEX1_SDB_CP2108_RX")
		)
		(pad "2" smd circle
			(at 0.40005 0 90)
			(size 0 0)
			(layers "F.Cu" "F.Mask" "F.Paste")
			(net "UART_PEX1_SDB_R_RX")
		)
	)
	(footprint ""
		(layer "F.Cu")
		(at 108.007404 -164.52342 180)
		(property "Reference" "PC26"
			(at 0 0 180)
			(layer "F.SilkS")
			(hide yes)
			(effects
				(font
					(size 1.27 1.27)
				)
			)
		)
		(property "Value" ""
			(at 0 0 180)
			(layer "F.Fab")
			(effects
				(font
					(size 1.27 1.27)
				)
			)
		)
		(duplicate_pad_numbers_are_jumpers no)
		(fp_line
			(start 1.524 0.762)
			(end -1.524 0.762)
			(stroke
				(width 0.1524)
				(type default)
			)
			(layer "F.SilkS")
		)
		(fp_line
			(start 1.524 -0.762)
			(end 1.524 0.762)
			(stroke
				(width 0.1524)
				(type default)
			)
			(layer "F.SilkS")
		)
		(fp_line
			(start -1.524 0.762)
			(end -1.524 -0.762)
			(stroke
				(width 0.1524)
				(type default)
			)
			(layer "F.SilkS")
		)
		(fp_line
			(start -1.524 -0.762)
			(end 1.524 -0.762)
			(stroke
				(width 0.1524)
				(type default)
			)
			(layer "F.SilkS")
		)
		(fp_line
			(start 1.1049 0.724916)
			(end 1.1049 -0.724916)
			(stroke
				(width 0.1)
				(type default)
			)
			(layer "F.Fab")
		)
		(fp_line
			(start 1.1049 -0.724916)
			(end -1.1049 -0.724916)
			(stroke
				(width 0.1)
				(type default)
			)
			(layer "F.Fab")
		)
		(fp_line
			(start -1.1049 0.724916)
			(end 1.1049 0.724916)
			(stroke
				(width 0.1)
				(type default)
			)
			(layer "F.Fab")
		)
		(fp_line
			(start -1.1049 -0.724916)
			(end -1.1049 0.724916)
			(stroke
				(width 0.1)
				(type default)
			)
			(layer "F.Fab")
		)
		(pad "1" smd rect
			(at -0.889 0)
			(size 1.016 1.27)
			(layers "F.Cu" "F.Mask" "F.Paste")
			(net "SW_P12V_P3V3_AUX_FLT")
		)
		(pad "2" smd rect
			(at 0.889 0)
			(size 1.016 1.27)
			(layers "F.Cu" "F.Mask" "F.Paste")
			(net "GND")
		)
	)
	(footprint ""
		(layer "F.Cu")
		(at 141.458442 -252.356874 -90)
		(property "Reference" "R1296"
			(at 0 0 270)
			(layer "F.SilkS")
			(hide yes)
			(effects
				(font
					(size 1.27 1.27)
				)
			)
		)
		(property "Value" ""
			(at 0 0 270)
			(layer "F.Fab")
			(effects
				(font
					(size 1.27 1.27)
				)
			)
		)
		(duplicate_pad_numbers_are_jumpers no)
		(fp_line
			(start -0.7874 0.4064)
			(end -0.7874 -0.4064)
			(stroke
				(width 0.1524)
				(type default)
			)
			(layer "F.SilkS")
		)
		(fp_line
			(start 0.7874 0.4064)
			(end -0.7874 0.4064)
			(stroke
				(width 0.1524)
				(type default)
			)
			(layer "F.SilkS")
		)
		(fp_line
			(start -0.7874 -0.4064)
			(end 0.7874 -0.4064)
			(stroke
				(width 0.1524)
				(type default)
			)
			(layer "F.SilkS")
		)
		(fp_line
			(start 0.7874 -0.4064)
			(end 0.7874 0.4064)
			(stroke
				(width 0.1524)
				(type default)
			)
			(layer "F.SilkS")
		)
		(fp_line
			(start -0.67945 0.3048)
			(end -0.67945 -0.305054)
			(stroke
				(width 0.1)
				(type default)
			)
			(layer "F.Fab")
		)
		(fp_line
			(start -0.12065 0.3048)
			(end -0.67945 0.3048)
			(stroke
				(width 0.1)
				(type default)
			)
			(layer "F.Fab")
		)
		(fp_line
			(start 0.120396 0.3048)
			(end 0.120396 0.2794)
			(stroke
				(width 0.1)
				(type default)
			)
			(layer "F.Fab")
		)
		(fp_line
			(start 0.67945 0.3048)
			(end 0.120396 0.3048)
			(stroke
				(width 0.1)
				(type default)
			)
			(layer "F.Fab")
		)
		(fp_line
			(start -0.12065 0.2794)
			(end -0.12065 0.3048)
			(stroke
				(width 0.1)
				(type default)
			)
			(layer "F.Fab")
		)
		(fp_line
			(start 0.120396 0.2794)
			(end -0.12065 0.2794)
			(stroke
				(width 0.1)
				(type default)
			)
			(layer "F.Fab")
		)
		(fp_line
			(start -0.12065 -0.2794)
			(end 0.12065 -0.2794)
			(stroke
				(width 0.1)
				(type default)
			)
			(layer "F.Fab")
		)
		(fp_line
			(start 0.12065 -0.2794)
			(end 0.12065 -0.3048)
			(stroke
				(width 0.1)
				(type default)
			)
			(layer "F.Fab")
		)
		(fp_line
			(start 0.12065 -0.3048)
			(end 0.67945 -0.3048)
			(stroke
				(width 0.1)
				(type default)
			)
			(layer "F.Fab")
		)
		(fp_line
			(start 0.67945 -0.3048)
			(end 0.67945 0.3048)
			(stroke
				(width 0.1)
				(type default)
			)
			(layer "F.Fab")
		)
		(fp_line
			(start -0.67945 -0.305054)
			(end -0.12065 -0.305054)
			(stroke
				(width 0.1)
				(type default)
			)
			(layer "F.Fab")
		)
		(fp_line
			(start -0.12065 -0.305054)
			(end -0.12065 -0.2794)
			(stroke
				(width 0.1)
				(type default)
			)
			(layer "F.Fab")
		)
		(pad "1" smd circle
			(at -0.40005 0 270)
			(size 0 0)
			(layers "F.Cu" "F.Mask" "F.Paste")
			(net "GND")
		)
		(pad "2" smd circle
			(at 0.40005 0 270)
			(size 0 0)
			(layers "F.Cu" "F.Mask" "F.Paste")
			(net "PEX1_MODE_SEL7")
		)
	)
	(footprint ""
		(layer "F.Cu")
		(at 67.564762 -356.244906 90)
		(property "Reference" "C135"
			(at 0 0 90)
			(layer "F.SilkS")
			(hide yes)
			(effects
				(font
					(size 1.27 1.27)
				)
			)
		)
		(property "Value" ""
			(at 0 0 90)
			(layer "F.Fab")
			(effects
				(font
					(size 1.27 1.27)
				)
			)
		)
		(duplicate_pad_numbers_are_jumpers no)
		(fp_line
			(start 0.299974 -0.150114)
			(end 0.299974 0.150114)
			(stroke
				(width 0.1)
				(type default)
			)
			(layer "F.Fab")
		)
		(fp_line
			(start -0.299974 -0.150114)
			(end 0.299974 -0.150114)
			(stroke
				(width 0.1)
				(type default)
			)
			(layer "F.Fab")
		)
		(fp_line
			(start 0.299974 0.150114)
			(end -0.299974 0.150114)
			(stroke
				(width 0.1)
				(type default)
			)
			(layer "F.Fab")
		)
		(fp_line
			(start -0.299974 0.150114)
			(end -0.299974 -0.150114)
			(stroke
				(width 0.1)
				(type default)
			)
			(layer "F.Fab")
		)
		(pad "1" smd rect
			(at -0.2667 0 90)
			(size 0.3048 0.381)
			(layers "F.Cu" "F.Mask" "F.Paste")
			(net "P5E_PEX0_STN6_TX_DP<108>")
		)
		(pad "2" smd rect
			(at 0.2667 0 90)
			(size 0.3048 0.381)
			(layers "F.Cu" "F.Mask" "F.Paste")
			(net "P5E_PEX0_STN6_TX_C_DP<108>")
		)
	)
	(footprint ""
		(layer "F.Cu")
		(at 324.271386 -96.811592 -90)
		(property "Reference" "R735"
			(at 0 0 270)
			(layer "F.SilkS")
			(hide yes)
			(effects
				(font
					(size 1.27 1.27)
				)
			)
		)
		(property "Value" ""
			(at 0 0 270)
			(layer "F.Fab")
			(effects
				(font
					(size 1.27 1.27)
				)
			)
		)
		(duplicate_pad_numbers_are_jumpers no)
		(fp_line
			(start -0.7874 0.4064)
			(end -0.7874 -0.4064)
			(stroke
				(width 0.1524)
				(type default)
			)
			(layer "F.SilkS")
		)
		(fp_line
			(start 0.7874 0.4064)
			(end -0.7874 0.4064)
			(stroke
				(width 0.1524)
				(type default)
			)
			(layer "F.SilkS")
		)
		(fp_line
			(start -0.7874 -0.4064)
			(end 0.7874 -0.4064)
			(stroke
				(width 0.1524)
				(type default)
			)
			(layer "F.SilkS")
		)
		(fp_line
			(start 0.7874 -0.4064)
			(end 0.7874 0.4064)
			(stroke
				(width 0.1524)
				(type default)
			)
			(layer "F.SilkS")
		)
		(fp_line
			(start -0.67945 0.3048)
			(end -0.67945 -0.305054)
			(stroke
				(width 0.1)
				(type default)
			)
			(layer "F.Fab")
		)
		(fp_line
			(start -0.12065 0.3048)
			(end -0.67945 0.3048)
			(stroke
				(width 0.1)
				(type default)
			)
			(layer "F.Fab")
		)
		(fp_line
			(start 0.120396 0.3048)
			(end 0.120396 0.2794)
			(stroke
				(width 0.1)
				(type default)
			)
			(layer "F.Fab")
		)
		(fp_line
			(start 0.67945 0.3048)
			(end 0.120396 0.3048)
			(stroke
				(width 0.1)
				(type default)
			)
			(layer "F.Fab")
		)
		(fp_line
			(start -0.12065 0.2794)
			(end -0.12065 0.3048)
			(stroke
				(width 0.1)
				(type default)
			)
			(layer "F.Fab")
		)
		(fp_line
			(start 0.120396 0.2794)
			(end -0.12065 0.2794)
			(stroke
				(width 0.1)
				(type default)
			)
			(layer "F.Fab")
		)
		(fp_line
			(start -0.12065 -0.2794)
			(end 0.12065 -0.2794)
			(stroke
				(width 0.1)
				(type default)
			)
			(layer "F.Fab")
		)
		(fp_line
			(start 0.12065 -0.2794)
			(end 0.12065 -0.3048)
			(stroke
				(width 0.1)
				(type default)
			)
			(layer "F.Fab")
		)
		(fp_line
			(start 0.12065 -0.3048)
			(end 0.67945 -0.3048)
			(stroke
				(width 0.1)
				(type default)
			)
			(layer "F.Fab")
		)
		(fp_line
			(start 0.67945 -0.3048)
			(end 0.67945 0.3048)
			(stroke
				(width 0.1)
				(type default)
			)
			(layer "F.Fab")
		)
		(fp_line
			(start -0.67945 -0.305054)
			(end -0.12065 -0.305054)
			(stroke
				(width 0.1)
				(type default)
			)
			(layer "F.Fab")
		)
		(fp_line
			(start -0.12065 -0.305054)
			(end -0.12065 -0.2794)
			(stroke
				(width 0.1)
				(type default)
			)
			(layer "F.Fab")
		)
		(pad "1" smd circle
			(at -0.40005 0 270)
			(size 0 0)
			(layers "F.Cu" "F.Mask" "F.Paste")
			(net "P3V3_AUX")
		)
		(pad "2" smd circle
			(at 0.40005 0 270)
			(size 0 0)
			(layers "F.Cu" "F.Mask" "F.Paste")
			(net "NIC_ADC_ALERT_N")
		)
	)
	(footprint ""
		(layer "F.Cu")
		(at 109.54639 -285.088584 90)
		(property "Reference" "PC74"
			(at 0 0 90)
			(layer "F.SilkS")
			(hide yes)
			(effects
				(font
					(size 1.27 1.27)
				)
			)
		)
		(property "Value" ""
			(at 0 0 90)
			(layer "F.Fab")
			(effects
				(font
					(size 1.27 1.27)
				)
			)
		)
		(duplicate_pad_numbers_are_jumpers no)
		(fp_line
			(start 0.7874 -0.4064)
			(end 0.7874 0.4064)
			(stroke
				(width 0.1524)
				(type default)
			)
			(layer "F.SilkS")
		)
		(fp_line
			(start -0.7874 -0.4064)
			(end 0.7874 -0.4064)
			(stroke
				(width 0.1524)
				(type default)
			)
			(layer "F.SilkS")
		)
		(fp_line
			(start 0.7874 0.4064)
			(end -0.7874 0.4064)
			(stroke
				(width 0.1524)
				(type default)
			)
			(layer "F.SilkS")
		)
		(fp_line
			(start -0.7874 0.4064)
			(end -0.7874 -0.4064)
			(stroke
				(width 0.1524)
				(type default)
			)
			(layer "F.SilkS")
		)
		(fp_line
			(start -0.12065 -0.305054)
			(end -0.12065 -0.2794)
			(stroke
				(width 0.1)
				(type default)
			)
			(layer "F.Fab")
		)
		(fp_line
			(start -0.67945 -0.305054)
			(end -0.12065 -0.305054)
			(stroke
				(width 0.1)
				(type default)
			)
			(layer "F.Fab")
		)
		(fp_line
			(start 0.67945 -0.3048)
			(end 0.67945 0.3048)
			(stroke
				(width 0.1)
				(type default)
			)
			(layer "F.Fab")
		)
		(fp_line
			(start 0.12065 -0.3048)
			(end 0.67945 -0.3048)
			(stroke
				(width 0.1)
				(type default)
			)
			(layer "F.Fab")
		)
		(fp_line
			(start 0.12065 -0.2794)
			(end 0.12065 -0.3048)
			(stroke
				(width 0.1)
				(type default)
			)
			(layer "F.Fab")
		)
		(fp_line
			(start -0.12065 -0.2794)
			(end 0.12065 -0.2794)
			(stroke
				(width 0.1)
				(type default)
			)
			(layer "F.Fab")
		)
		(fp_line
			(start 0.120396 0.2794)
			(end -0.12065 0.2794)
			(stroke
				(width 0.1)
				(type default)
			)
			(layer "F.Fab")
		)
		(fp_line
			(start -0.12065 0.2794)
			(end -0.12065 0.3048)
			(stroke
				(width 0.1)
				(type default)
			)
			(layer "F.Fab")
		)
		(fp_line
			(start 0.67945 0.3048)
			(end 0.120396 0.3048)
			(stroke
				(width 0.1)
				(type default)
			)
			(layer "F.Fab")
		)
		(fp_line
			(start 0.120396 0.3048)
			(end 0.120396 0.2794)
			(stroke
				(width 0.1)
				(type default)
			)
			(layer "F.Fab")
		)
		(fp_line
			(start -0.12065 0.3048)
			(end -0.67945 0.3048)
			(stroke
				(width 0.1)
				(type default)
			)
			(layer "F.Fab")
		)
		(fp_line
			(start -0.67945 0.3048)
			(end -0.67945 -0.305054)
			(stroke
				(width 0.1)
				(type default)
			)
			(layer "F.Fab")
		)
		(pad "1" smd circle
			(at -0.40005 0 90)
			(size 0 0)
			(layers "F.Cu" "F.Mask" "F.Paste")
			(net "P0V8_PEX0_PVCC")
		)
		(pad "2" smd circle
			(at 0.40005 0 90)
			(size 0 0)
			(layers "F.Cu" "F.Mask" "F.Paste")
			(net "GND")
		)
	)
	(footprint ""
		(layer "F.Cu")
		(at 281.221942 -343.952322 90)
		(property "Reference" "C2352"
			(at 0 0 90)
			(layer "F.SilkS")
			(hide yes)
			(effects
				(font
					(size 1.27 1.27)
				)
			)
		)
		(property "Value" ""
			(at 0 0 90)
			(layer "F.Fab")
			(effects
				(font
					(size 1.27 1.27)
				)
			)
		)
		(duplicate_pad_numbers_are_jumpers no)
		(fp_line
			(start 0.299974 -0.150114)
			(end 0.299974 0.150114)
			(stroke
				(width 0.1)
				(type default)
			)
			(layer "F.Fab")
		)
		(fp_line
			(start -0.299974 -0.150114)
			(end 0.299974 -0.150114)
			(stroke
				(width 0.1)
				(type default)
			)
			(layer "F.Fab")
		)
		(fp_line
			(start 0.299974 0.150114)
			(end -0.299974 0.150114)
			(stroke
				(width 0.1)
				(type default)
			)
			(layer "F.Fab")
		)
		(fp_line
			(start -0.299974 0.150114)
			(end -0.299974 -0.150114)
			(stroke
				(width 0.1)
				(type default)
			)
			(layer "F.Fab")
		)
		(pad "1" smd rect
			(at -0.2667 0 90)
			(size 0.3048 0.381)
			(layers "F.Cu" "F.Mask" "F.Paste")
			(net "P5E_PEX2_STN4_TX_DN<74>")
		)
		(pad "2" smd rect
			(at 0.2667 0 90)
			(size 0.3048 0.381)
			(layers "F.Cu" "F.Mask" "F.Paste")
			(net "P5E_PEX2_STN4_TX_C_DN<74>")
		)
	)
	(footprint ""
		(layer "F.Cu")
		(at 115.356386 -85.384386 180)
		(property "Reference" "R1145"
			(at 0 0 180)
			(layer "F.SilkS")
			(hide yes)
			(effects
				(font
					(size 1.27 1.27)
				)
			)
		)
		(property "Value" ""
			(at 0 0 180)
			(layer "F.Fab")
			(effects
				(font
					(size 1.27 1.27)
				)
			)
		)
		(duplicate_pad_numbers_are_jumpers no)
		(fp_line
			(start 0.7874 0.4064)
			(end -0.7874 0.4064)
			(stroke
				(width 0.1524)
				(type default)
			)
			(layer "F.SilkS")
		)
		(fp_line
			(start 0.67945 0.3048)
			(end 0.120396 0.3048)
			(stroke
				(width 0.1)
				(type default)
			)
			(layer "F.Fab")
		)
		(fp_line
			(start 0.67945 -0.3048)
			(end 0.67945 0.3048)
			(stroke
				(width 0.1)
				(type default)
			)
			(layer "F.Fab")
		)
		(fp_line
			(start 0.12065 -0.2794)
			(end 0.12065 -0.3048)
			(stroke
				(width 0.1)
				(type default)
			)
			(layer "F.Fab")
		)
		(fp_line
			(start 0.12065 -0.3048)
			(end 0.67945 -0.3048)
			(stroke
				(width 0.1)
				(type default)
			)
			(layer "F.Fab")
		)
		(fp_line
			(start 0.120396 0.3048)
			(end 0.120396 0.2794)
			(stroke
				(width 0.1)
				(type default)
			)
			(layer "F.Fab")
		)
		(fp_line
			(start 0.120396 0.2794)
			(end -0.12065 0.2794)
			(stroke
				(width 0.1)
				(type default)
			)
			(layer "F.Fab")
		)
		(fp_line
			(start -0.12065 0.3048)
			(end -0.67945 0.3048)
			(stroke
				(width 0.1)
				(type default)
			)
			(layer "F.Fab")
		)
		(fp_line
			(start -0.12065 0.2794)
			(end -0.12065 0.3048)
			(stroke
				(width 0.1)
				(type default)
			)
			(layer "F.Fab")
		)
		(fp_line
			(start -0.12065 -0.2794)
			(end 0.12065 -0.2794)
			(stroke
				(width 0.1)
				(type default)
			)
			(layer "F.Fab")
		)
		(fp_line
			(start -0.12065 -0.305054)
			(end -0.12065 -0.2794)
			(stroke
				(width 0.1)
				(type default)
			)
			(layer "F.Fab")
		)
		(fp_line
			(start -0.67945 0.3048)
			(end -0.67945 -0.305054)
			(stroke
				(width 0.1)
				(type default)
			)
			(layer "F.Fab")
		)
		(fp_line
			(start -0.67945 -0.305054)
			(end -0.12065 -0.305054)
			(stroke
				(width 0.1)
				(type default)
			)
			(layer "F.Fab")
		)
		(pad "1" smd circle
			(at -0.40005 0 180)
			(size 0 0)
			(layers "F.Cu" "F.Mask" "F.Paste")
			(net "CLK_100M_DB800ZL_SSD4_R_DN")
		)
		(pad "2" smd circle
			(at 0.40005 0 180)
			(size 0 0)
			(layers "F.Cu" "F.Mask" "F.Paste")
			(net "CLK_100M_DB800ZL_SSD4_DN")
		)
	)
)
